# BASEBOARD_FAB2 (Tioga Pass) — schematic netlist excerpt (pin names and nets, part order shuffled) for the footprints in the layout excerpt that follows; sources: Cadence DE-HDL packaged netlist, KiCad conversion of Wiwynn_Tioga_Pass_MB.brd

R2U5  RES  2.26K 1.0% CHIP  pkg 0402  page 159 : A = P3V3_STBY ; B = SMB_OCP_FRU_STBY_LVC3_SCL_R
C2N18  CAP_A  1.0UF 6.3V 10% X6S  pkg 0402V  page 130 : A = P3V3_STBY ; B = GND
R1U32  RES  5.11K 1% CHIP  pkg 0402  page 169 : A = P12V_STBY ; B = A_P12V_STBY_SCALED

(kicad_pcb
	(version 20260206)
	(generator "pcbnew")
	(generator_version "10.0")
	(general
		(thickness 1.6)
		(legacy_teardrops no)
	)
	(paper "A4")
	(title_block
		(title "Wiwynn_Tioga_Pass_MB.brd")
		(comment 1 "Tioga Pass / footprints 3013-3015 of 4770")
	)
	(layers
		(0 "F.Cu" signal "TOP")
		(4 "In1.Cu" signal "L2GND")
		(6 "In2.Cu" signal "L3")
		(8 "In3.Cu" signal "L4GND")
		(10 "In4.Cu" signal "L5")
		(12 "In5.Cu" signal "L6GND")
		(14 "In6.Cu" signal "L7VCC")
		(16 "In7.Cu" signal "L8VCC")
		(18 "In8.Cu" signal "L9GND")
		(20 "In9.Cu" signal "L10")
		(22 "In10.Cu" signal "L11GND")
		(24 "In11.Cu" signal "L12")
		(26 "In12.Cu" signal "L13GND")
		(2 "B.Cu" signal "BOTTOM")
		(9 "F.Adhes" user "F.Adhesive")
		(11 "B.Adhes" user "B.Adhesive")
		(13 "F.Paste" user "Package Geometry/Pastemask Top")
		(15 "B.Paste" user "Package Geometry/Pastemask Bottom")
		(5 "F.SilkS" user "Ref Des/Silkscreen Top")
		(7 "B.SilkS" user "Ref Des/Silkscreen Bottom")
		(1 "F.Mask" user "Board Geometry/Soldermask Top")
		(3 "B.Mask" user "Board Geometry/Soldermask Bottom")
		(17 "Dwgs.User" user "User.Drawings")
		(19 "Cmts.User" user "User.Comments")
		(21 "Eco1.User" user "User.Eco1")
		(23 "Eco2.User" user "User.Eco2")
		(25 "Edge.Cuts" user "Board Geometry/Outline")
		(27 "Margin" user)
		(31 "F.CrtYd" user "Package Geometry/Place Bound Top")
		(29 "B.CrtYd" user "Package Geometry/Place Bound Bottom")
		(35 "F.Fab" user "Ref Des/Assembly Top")
		(33 "B.Fab" user "Ref Des/Assembly Bottom")
	)
	(footprint ""
		(layer "B.Cu")
		(at 401.5613 -39.5224 90)
		(property "Reference" "R2U5"
			(at 0 0 90)
			(layer "B.SilkS")
			(hide yes)
			(effects
				(font
					(size 1.27 1.27)
				)
				(justify mirror)
			)
		)
		(property "Value" ""
			(at 0 0 90)
			(layer "B.Fab")
			(effects
				(font
					(size 1.27 1.27)
				)
				(justify mirror)
			)
		)
		(duplicate_pad_numbers_are_jumpers no)
		(fp_poly
			(pts
				(xy 0.2794 -0.1016) (xy -0.2794 -0.1016) (xy -0.2794 0.9906) (xy 0.2794 0.9906)
			)
			(stroke
				(width 0)
				(type default)
			)
			(fill no)
			(layer "B.CrtYd")
		)
		(fp_line
			(start 0.2794 -0.1016)
			(end 0.2794 0.9906)
			(stroke
				(width 0.1)
				(type default)
			)
			(layer "B.Fab")
		)
		(fp_line
			(start -0.2794 -0.1016)
			(end 0.2794 -0.1016)
			(stroke
				(width 0.1)
				(type default)
			)
			(layer "B.Fab")
		)
		(fp_line
			(start 0.2794 0.9906)
			(end -0.2794 0.9906)
			(stroke
				(width 0.1)
				(type default)
			)
			(layer "B.Fab")
		)
		(fp_line
			(start -0.2794 0.9906)
			(end -0.2794 -0.1016)
			(stroke
				(width 0.1)
				(type default)
			)
			(layer "B.Fab")
		)
		(pad "1" smd rect
			(at 0 0 270)
			(size 0.508 0.508)
			(layers "B.Cu" "B.Mask" "B.Paste")
			(net "P3V3_STBY")
		)
		(pad "2" smd rect
			(at 0 0.889 270)
			(size 0.508 0.508)
			(layers "B.Cu" "B.Mask" "B.Paste")
			(net "SMB_OCP_FRU_STBY_LVC3_SCL_R")
		)
		(zone
			(layer "B.Cu")
			(hatch none 0.5)
			(connect_pads
				(clearance 0)
			)
			(min_thickness 0.25)
			(keepout
				(tracks allowed)
				(vias not_allowed)
				(pads allowed)
				(copperpour not_allowed)
				(footprints allowed)
			)
			(placement
				(enabled no)
				(sheetname "")
			)
			(fill
				(thermal_gap 0.5)
				(thermal_bridge_width 0.5)
				(island_removal_mode 0)
			)
			(polygon
				(pts
					(xy 401.8153 -39.7764) (xy 401.8153 -39.2684) (xy 402.1963 -39.2684) (xy 402.1963 -39.7764)
				)
			)
		)
		(zone
			(layer "B.Cu")
			(hatch none 0.5)
			(connect_pads
				(clearance 0)
			)
			(min_thickness 0.25)
			(keepout
				(tracks not_allowed)
				(vias allowed)
				(pads allowed)
				(copperpour not_allowed)
				(footprints allowed)
			)
			(placement
				(enabled no)
				(sheetname "")
			)
			(fill
				(thermal_gap 0.5)
				(thermal_bridge_width 0.5)
				(island_removal_mode 0)
			)
			(polygon
				(pts
					(xy 402.1963 -39.7764) (xy 402.1963 -39.2684) (xy 401.8153 -39.2684) (xy 401.8153 -39.7764)
				)
			)
		)
	)
	(footprint ""
		(layer "B.Cu")
		(at 390.93775 -105.45445)
		(property "Reference" "C2N18"
			(at 0 0 0)
			(layer "B.SilkS")
			(hide yes)
			(effects
				(font
					(size 1.27 1.27)
				)
				(justify mirror)
			)
		)
		(property "Value" ""
			(at 0 0 0)
			(layer "B.Fab")
			(effects
				(font
					(size 1.27 1.27)
				)
				(justify mirror)
			)
		)
		(duplicate_pad_numbers_are_jumpers no)
		(fp_rect
			(start 0.2794 0.9144)
			(end -0.2794 -0.1143)
			(stroke
				(width 0)
				(type default)
			)
			(fill no)
			(layer "B.CrtYd")
		)
		(fp_line
			(start -0.2794 -0.1143)
			(end -0.2794 0.9144)
			(stroke
				(width 0.1)
				(type default)
			)
			(layer "B.Fab")
		)
		(fp_line
			(start -0.2794 0.9144)
			(end 0.2794 0.9144)
			(stroke
				(width 0.1)
				(type default)
			)
			(layer "B.Fab")
		)
		(fp_line
			(start 0.2794 -0.1143)
			(end -0.2794 -0.1143)
			(stroke
				(width 0.1)
				(type default)
			)
			(layer "B.Fab")
		)
		(fp_line
			(start 0.2794 0.9144)
			(end 0.2794 -0.1143)
			(stroke
				(width 0.1)
				(type default)
			)
			(layer "B.Fab")
		)
		(pad "1" smd custom
			(at 0 0 270)
			(size 0.10414 0.10414)
			(layers "B.Cu" "B.Mask" "B.Paste")
			(net "P3V3_STBY")
			(options
				(clearance outline)
				(anchor circle)
			)
			(primitives
				(gr_poly
					(pts
						(xy -0.20828 -0.08636) (xy -0.20828 0.08636) (xy -0.08636 0.20828) (xy 0.086614 0.20828) (xy 0.20828 0.086614)
						(xy 0.20828 -0.08636) (xy 0.08636 -0.20828) (xy -0.08636 -0.20828)
					)
					(width 0)
					(fill yes)
				)
			)
		)
		(pad "2" smd custom
			(at 0 0.8001 270)
			(size 0.10414 0.10414)
			(layers "B.Cu" "B.Mask" "B.Paste")
			(net "GND")
			(options
				(clearance outline)
				(anchor circle)
			)
			(primitives
				(gr_poly
					(pts
						(xy -0.20828 -0.08636) (xy -0.20828 0.08636) (xy -0.08636 0.20828) (xy 0.086614 0.20828) (xy 0.20828 0.086614)
						(xy 0.20828 -0.08636) (xy 0.08636 -0.20828) (xy -0.08636 -0.20828)
					)
					(width 0)
					(fill yes)
				)
			)
		)
		(zone
			(layer "B.Cu")
			(hatch none 0.5)
			(connect_pads
				(clearance 0)
			)
			(min_thickness 0.25)
			(keepout
				(tracks not_allowed)
				(vias allowed)
				(pads allowed)
				(copperpour not_allowed)
				(footprints allowed)
			)
			(placement
				(enabled no)
				(sheetname "")
			)
			(fill
				(thermal_gap 0.5)
				(thermal_bridge_width 0.5)
				(island_removal_mode 0)
			)
			(polygon
				(pts
					(xy 391.02538 -105.2449) (xy 391.02538 -104.8639) (xy 390.85012 -104.8639) (xy 390.849866 -105.2449)
				)
			)
		)
		(zone
			(layer "B.Cu")
			(hatch none 0.5)
			(connect_pads
				(clearance 0)
			)
			(min_thickness 0.25)
			(keepout
				(tracks allowed)
				(vias not_allowed)
				(pads allowed)
				(copperpour not_allowed)
				(footprints allowed)
			)
			(placement
				(enabled no)
				(sheetname "")
			)
			(fill
				(thermal_gap 0.5)
				(thermal_bridge_width 0.5)
				(island_removal_mode 0)
			)
			(polygon
				(pts
					(xy 391.02538 -105.2449) (xy 391.02538 -104.8639) (xy 390.85012 -104.8639) (xy 390.849866 -105.2449)
				)
			)
		)
	)
	(footprint ""
		(layer "B.Cu")
		(at 401.108418 -26.471372 180)
		(property "Reference" "R1U32"
			(at 0 0 0)
			(layer "B.SilkS")
			(hide yes)
			(effects
				(font
					(size 1.27 1.27)
				)
				(justify mirror)
			)
		)
		(property "Value" ""
			(at 0 0 0)
			(layer "B.Fab")
			(effects
				(font
					(size 1.27 1.27)
				)
				(justify mirror)
			)
		)
		(duplicate_pad_numbers_are_jumpers no)
		(fp_poly
			(pts
				(xy 0.2794 -0.1016) (xy -0.2794 -0.1016) (xy -0.2794 0.9906) (xy 0.2794 0.9906)
			)
			(stroke
				(width 0)
				(type default)
			)
			(fill no)
			(layer "B.CrtYd")
		)
		(fp_line
			(start 0.2794 0.9906)
			(end -0.2794 0.9906)
			(stroke
				(width 0.1)
				(type default)
			)
			(layer "B.Fab")
		)
		(fp_line
			(start 0.2794 -0.1016)
			(end 0.2794 0.9906)
			(stroke
				(width 0.1)
				(type default)
			)
			(layer "B.Fab")
		)
		(fp_line
			(start -0.2794 0.9906)
			(end -0.2794 -0.1016)
			(stroke
				(width 0.1)
				(type default)
			)
			(layer "B.Fab")
		)
		(fp_line
			(start -0.2794 -0.1016)
			(end 0.2794 -0.1016)
			(stroke
				(width 0.1)
				(type default)
			)
			(layer "B.Fab")
		)
		(pad "1" smd rect
			(at 0 0)
			(size 0.508 0.508)
			(layers "B.Cu" "B.Mask" "B.Paste")
			(net "P12V_STBY")
		)
		(pad "2" smd rect
			(at 0 0.889)
			(size 0.508 0.508)
			(layers "B.Cu" "B.Mask" "B.Paste")
			(net "A_P12V_STBY_SCALED")
		)
		(zone
			(layer "B.Cu")
			(hatch none 0.5)
			(connect_pads
				(clearance 0)
			)
			(min_thickness 0.25)
			(keepout
				(tracks not_allowed)
				(vias allowed)
				(pads allowed)
				(copperpour not_allowed)
				(footprints allowed)
			)
			(placement
				(enabled no)
				(sheetname "")
			)
			(fill
				(thermal_gap 0.5)
				(thermal_bridge_width 0.5)
				(island_removal_mode 0)
			)
			(polygon
				(pts
					(xy 400.854418 -27.106372) (xy 401.362418 -27.106372) (xy 401.362418 -26.725372) (xy 400.854418 -26.725372)
				)
			)
		)
		(zone
			(layer "B.Cu")
			(hatch none 0.5)
			(connect_pads
				(clearance 0)
			)
			(min_thickness 0.25)
			(keepout
				(tracks allowed)
				(vias not_allowed)
				(pads allowed)
				(copperpour not_allowed)
				(footprints allowed)
			)
			(placement
				(enabled no)
				(sheetname "")
			)
			(fill
				(thermal_gap 0.5)
				(thermal_bridge_width 0.5)
				(island_removal_mode 0)
			)
			(polygon
				(pts
					(xy 400.854418 -26.725372) (xy 401.362418 -26.725372) (xy 401.362418 -27.106372) (xy 400.854418 -27.106372)
				)
			)
		)
	)
)
